(kicad_pcb
	(version 20260206)
	(generator "pcbnew")
	(generator_version "10.0")
	(general
		(thickness 1.6)
		(legacy_teardrops no)
	)
	(paper "A4")
	(title_block
		(title "peb — Lightning_PEB_BRD.brd")
		(comment 1 "Lightning (Wiwynn / Facebook NVMe JBOF) / footprints 2161-2167 of 2563")
	)
	(layers
		(0 "F.Cu" signal "TOP")
		(4 "In1.Cu" signal "L2GND")
		(6 "In2.Cu" signal "L3")
		(8 "In3.Cu" signal "L4VCC")
		(10 "In4.Cu" signal "L5VCC")
		(12 "In5.Cu" signal "L6")
		(14 "In6.Cu" signal "L7GND")
		(2 "B.Cu" signal "BOTTOM")
		(9 "F.Adhes" user "F.Adhesive")
		(11 "B.Adhes" user "B.Adhesive")
		(13 "F.Paste" user "Package Geometry/Pastemask Top")
		(15 "B.Paste" user "Package Geometry/Pastemask Bottom")
		(5 "F.SilkS" user "Ref Des/Silkscreen Top")
		(7 "B.SilkS" user "Ref Des/Silkscreen Bottom")
		(1 "F.Mask" user "Board Geometry/Soldermask Top")
		(3 "B.Mask" user "Board Geometry/Soldermask Bottom")
		(17 "Dwgs.User" user "User.Drawings")
		(19 "Cmts.User" user "User.Comments")
		(21 "Eco1.User" user "User.Eco1")
		(23 "Eco2.User" user "User.Eco2")
		(25 "Edge.Cuts" user "Board Geometry/Outline")
		(27 "Margin" user)
		(31 "F.CrtYd" user "Package Geometry/Place Bound Top")
		(29 "B.CrtYd" user "Package Geometry/Place Bound Bottom")
		(35 "F.Fab" user "Ref Des/Assembly Top")
		(33 "B.Fab" user "Ref Des/Assembly Bottom")
	)
	(footprint ""
		(layer "B.Cu")
		(at 210.884008 -4.064)
		(property "Reference" "R3712"
			(at 0 0 0)
			(layer "B.SilkS")
			(hide yes)
			(effects
				(font
					(size 1.27 1.27)
				)
				(justify mirror)
			)
		)
		(property "Value" "1KR2F-3-GP"
			(at -0.064008 -3.993896 0)
			(unlocked yes)
			(layer "B.Fab")
			(hide yes)
			(effects
				(font
					(size 1.016 1.016)
					(thickness 0.1524)
				)
				(justify mirror)
			)
		)
		(property "Device Type" "R402H16"
			(at -0.064008 -5.517896 0)
			(unlocked yes)
			(layer "B.Fab")
			(hide yes)
			(effects
				(font
					(size 1.016 1.016)
					(thickness 0.1524)
				)
				(justify mirror)
			)
		)
		(duplicate_pad_numbers_are_jumpers no)
		(fp_line
			(start -0.508 -0.9398)
			(end 0.508 -0.9398)
			(stroke
				(width 0.1524)
				(type default)
			)
			(layer "B.SilkS")
		)
		(fp_line
			(start 0.508 -0.9398)
			(end 0.508 0.9398)
			(stroke
				(width 0.1524)
				(type default)
			)
			(layer "B.SilkS")
		)
		(fp_rect
			(start 0.508 0.9398)
			(end -0.508 -0.9398)
			(stroke
				(width 0)
				(type default)
			)
			(fill no)
			(layer "B.CrtYd")
		)
		(fp_rect
			(start 0.508 0.9398)
			(end -0.508 -0.9398)
			(stroke
				(width 0)
				(type default)
			)
			(fill no)
			(layer "B.Fab")
		)
		(pad "1" smd custom
			(at 0 -0.4445 180)
			(size 0.1397 0.1397)
			(layers "B.Cu" "B.Mask" "B.Paste")
			(net "HOST6_RST_N")
			(options
				(clearance outline)
				(anchor circle)
			)
			(primitives
				(gr_poly
					(pts
						(arc
							(start -0.1778 0.2794)
							(mid -0.249642 0.249642)
							(end -0.2794 0.1778)
						)
						(arc
							(start -0.2794 -0.1778)
							(mid -0.249642 -0.249642)
							(end -0.1778 -0.2794)
						)
						(arc
							(start 0.1778 -0.2794)
							(mid 0.249642 -0.249642)
							(end 0.2794 -0.1778)
						)
						(arc
							(start 0.2794 0.1778)
							(mid 0.249642 0.249642)
							(end 0.1778 0.2794)
						)
					)
					(width 0)
					(fill yes)
				)
			)
		)
		(pad "2" smd custom
			(at 0 0.4445 180)
			(size 0.1397 0.1397)
			(layers "B.Cu" "B.Mask" "B.Paste")
			(net "P3V3_STBY")
			(options
				(clearance outline)
				(anchor circle)
			)
			(primitives
				(gr_poly
					(pts
						(arc
							(start -0.1778 0.2794)
							(mid -0.249642 0.249642)
							(end -0.2794 0.1778)
						)
						(arc
							(start -0.2794 -0.1778)
							(mid -0.249642 -0.249642)
							(end -0.1778 -0.2794)
						)
						(arc
							(start 0.1778 -0.2794)
							(mid 0.249642 -0.249642)
							(end 0.2794 -0.1778)
						)
						(arc
							(start 0.2794 0.1778)
							(mid 0.249642 0.249642)
							(end 0.1778 0.2794)
						)
					)
					(width 0)
					(fill yes)
				)
			)
		)
	)
	(footprint ""
		(layer "B.Cu")
		(at 50.927 -104.14 180)
		(property "Reference" "R331"
			(at 0 0 0)
			(layer "B.SilkS")
			(hide yes)
			(effects
				(font
					(size 1.27 1.27)
				)
				(justify mirror)
			)
		)
		(property "Value" "4K7R2F-GP"
			(at -0.064008 -3.993896 180)
			(unlocked yes)
			(layer "B.Fab")
			(hide yes)
			(effects
				(font
					(size 1.016 1.016)
					(thickness 0.1524)
				)
				(justify mirror)
			)
		)
		(property "Device Type" "R402H16"
			(at -0.064008 -5.517896 180)
			(unlocked yes)
			(layer "B.Fab")
			(hide yes)
			(effects
				(font
					(size 1.016 1.016)
					(thickness 0.1524)
				)
				(justify mirror)
			)
		)
		(duplicate_pad_numbers_are_jumpers no)
		(fp_line
			(start 0.508 -0.9398)
			(end 0.508 0.9398)
			(stroke
				(width 0.1524)
				(type default)
			)
			(layer "B.SilkS")
		)
		(fp_line
			(start -0.508 -0.9398)
			(end 0.508 -0.9398)
			(stroke
				(width 0.1524)
				(type default)
			)
			(layer "B.SilkS")
		)
		(fp_rect
			(start 0.508 0.9398)
			(end -0.508 -0.9398)
			(stroke
				(width 0)
				(type default)
			)
			(fill no)
			(layer "B.CrtYd")
		)
		(fp_rect
			(start 0.508 0.9398)
			(end -0.508 -0.9398)
			(stroke
				(width 0)
				(type default)
			)
			(fill no)
			(layer "B.Fab")
		)
		(pad "1" smd custom
			(at 0 -0.4445)
			(size 0.1397 0.1397)
			(layers "B.Cu" "B.Mask" "B.Paste")
			(net "P3V3_STBY")
			(options
				(clearance outline)
				(anchor circle)
			)
			(primitives
				(gr_poly
					(pts
						(arc
							(start -0.1778 0.2794)
							(mid -0.249642 0.249642)
							(end -0.2794 0.1778)
						)
						(arc
							(start -0.2794 -0.1778)
							(mid -0.249642 -0.249642)
							(end -0.1778 -0.2794)
						)
						(arc
							(start 0.1778 -0.2794)
							(mid 0.249642 -0.249642)
							(end 0.2794 -0.1778)
						)
						(arc
							(start 0.2794 0.1778)
							(mid 0.249642 0.249642)
							(end 0.1778 0.2794)
						)
					)
					(width 0)
					(fill yes)
				)
			)
		)
		(pad "2" smd custom
			(at 0 0.4445)
			(size 0.1397 0.1397)
			(layers "B.Cu" "B.Mask" "B.Paste")
			(net "I2C8_LS_G2")
			(options
				(clearance outline)
				(anchor circle)
			)
			(primitives
				(gr_poly
					(pts
						(arc
							(start -0.1778 0.2794)
							(mid -0.249642 0.249642)
							(end -0.2794 0.1778)
						)
						(arc
							(start -0.2794 -0.1778)
							(mid -0.249642 -0.249642)
							(end -0.1778 -0.2794)
						)
						(arc
							(start 0.1778 -0.2794)
							(mid 0.249642 -0.249642)
							(end 0.2794 -0.1778)
						)
						(arc
							(start 0.2794 0.1778)
							(mid 0.249642 0.249642)
							(end 0.1778 0.2794)
						)
					)
					(width 0)
					(fill yes)
				)
			)
		)
	)
	(footprint ""
		(layer "B.Cu")
		(at 221.8182 -13.3858 90)
		(property "Reference" "C373"
			(at 0 0 90)
			(layer "B.SilkS")
			(hide yes)
			(effects
				(font
					(size 1.27 1.27)
				)
				(justify mirror)
			)
		)
		(property "Value" "SCD1U25V2KX-2-GP"
			(at -1.1811 -2.7051 90)
			(unlocked yes)
			(layer "B.Fab")
			(hide yes)
			(effects
				(font
					(size 1.016 1.016)
					(thickness 0.1524)
				)
				(justify mirror)
			)
		)
		(property "Device Type" "C402H22"
			(at -1.1811 -4.2291 90)
			(unlocked yes)
			(layer "B.Fab")
			(hide yes)
			(effects
				(font
					(size 1.016 1.016)
					(thickness 0.1524)
				)
				(justify mirror)
			)
		)
		(duplicate_pad_numbers_are_jumpers no)
		(fp_rect
			(start 0.4318 0.9525)
			(end -0.4318 -0.9525)
			(stroke
				(width 0)
				(type default)
			)
			(fill no)
			(layer "B.CrtYd")
		)
		(fp_rect
			(start 0.4318 0.9525)
			(end -0.4318 -0.9525)
			(stroke
				(width 0)
				(type default)
			)
			(fill no)
			(layer "B.Fab")
		)
		(pad "1" smd custom
			(at 0 -0.4445 270)
			(size 0.1524 0.1524)
			(layers "B.Cu" "B.Mask" "B.Paste")
			(net "P3V3_STBY")
			(options
				(clearance outline)
				(anchor circle)
			)
			(primitives
				(gr_poly
					(pts
						(arc
							(start 0.3048 0.2032)
							(mid 0.275042 0.275042)
							(end 0.2032 0.3048)
						)
						(arc
							(start -0.2032 0.3048)
							(mid -0.275042 0.275042)
							(end -0.3048 0.2032)
						)
						(arc
							(start -0.3048 -0.2032)
							(mid -0.275042 -0.275042)
							(end -0.2032 -0.3048)
						)
						(arc
							(start 0.2032 -0.3048)
							(mid 0.275042 -0.275042)
							(end 0.3048 -0.2032)
						)
					)
					(width 0)
					(fill yes)
				)
			)
		)
		(pad "2" smd custom
			(at 0 0.4445 270)
			(size 0.1524 0.1524)
			(layers "B.Cu" "B.Mask" "B.Paste")
			(net "GND")
			(options
				(clearance outline)
				(anchor circle)
			)
			(primitives
				(gr_poly
					(pts
						(arc
							(start 0.3048 0.2032)
							(mid 0.275042 0.275042)
							(end 0.2032 0.3048)
						)
						(arc
							(start -0.2032 0.3048)
							(mid -0.275042 0.275042)
							(end -0.3048 0.2032)
						)
						(arc
							(start -0.3048 -0.2032)
							(mid -0.275042 -0.275042)
							(end -0.2032 -0.3048)
						)
						(arc
							(start 0.2032 -0.3048)
							(mid 0.275042 -0.275042)
							(end 0.3048 -0.2032)
						)
					)
					(width 0)
					(fill yes)
				)
			)
		)
	)
	(footprint ""
		(layer "B.Cu")
		(at 337.852512 -172.432218)
		(property "Reference" "R4160"
			(at 0 0 0)
			(layer "B.SilkS")
			(hide yes)
			(effects
				(font
					(size 1.27 1.27)
				)
				(justify mirror)
			)
		)
		(property "Value" "4K7R2F-GP"
			(at -0.064008 -3.993896 0)
			(unlocked yes)
			(layer "B.Fab")
			(hide yes)
			(effects
				(font
					(size 1.016 1.016)
					(thickness 0.1524)
				)
				(justify mirror)
			)
		)
		(property "Device Type" "R402H16"
			(at -0.064008 -5.517896 0)
			(unlocked yes)
			(layer "B.Fab")
			(hide yes)
			(effects
				(font
					(size 1.016 1.016)
					(thickness 0.1524)
				)
				(justify mirror)
			)
		)
		(duplicate_pad_numbers_are_jumpers no)
		(fp_line
			(start -0.508 -0.9398)
			(end 0.508 -0.9398)
			(stroke
				(width 0.1524)
				(type default)
			)
			(layer "B.SilkS")
		)
		(fp_line
			(start 0.508 -0.9398)
			(end 0.508 0.9398)
			(stroke
				(width 0.1524)
				(type default)
			)
			(layer "B.SilkS")
		)
		(fp_rect
			(start 0.508 0.9398)
			(end -0.508 -0.9398)
			(stroke
				(width 0)
				(type default)
			)
			(fill no)
			(layer "B.CrtYd")
		)
		(fp_rect
			(start 0.508 0.9398)
			(end -0.508 -0.9398)
			(stroke
				(width 0)
				(type default)
			)
			(fill no)
			(layer "B.Fab")
		)
		(pad "1" smd custom
			(at 0 -0.4445 180)
			(size 0.1397 0.1397)
			(layers "B.Cu" "B.Mask" "B.Paste")
			(net "SSD_ATNLED#9")
			(options
				(clearance outline)
				(anchor circle)
			)
			(primitives
				(gr_poly
					(pts
						(arc
							(start -0.1778 0.2794)
							(mid -0.249642 0.249642)
							(end -0.2794 0.1778)
						)
						(arc
							(start -0.2794 -0.1778)
							(mid -0.249642 -0.249642)
							(end -0.1778 -0.2794)
						)
						(arc
							(start 0.1778 -0.2794)
							(mid 0.249642 -0.249642)
							(end 0.2794 -0.1778)
						)
						(arc
							(start 0.2794 0.1778)
							(mid 0.249642 0.249642)
							(end 0.1778 0.2794)
						)
					)
					(width 0)
					(fill yes)
				)
			)
		)
		(pad "2" smd custom
			(at 0 0.4445 180)
			(size 0.1397 0.1397)
			(layers "B.Cu" "B.Mask" "B.Paste")
			(net "P3V3_STBY")
			(options
				(clearance outline)
				(anchor circle)
			)
			(primitives
				(gr_poly
					(pts
						(arc
							(start -0.1778 0.2794)
							(mid -0.249642 0.249642)
							(end -0.2794 0.1778)
						)
						(arc
							(start -0.2794 -0.1778)
							(mid -0.249642 -0.249642)
							(end -0.1778 -0.2794)
						)
						(arc
							(start 0.1778 -0.2794)
							(mid 0.249642 -0.249642)
							(end 0.2794 -0.1778)
						)
						(arc
							(start 0.2794 0.1778)
							(mid 0.249642 0.249642)
							(end 0.1778 0.2794)
						)
					)
					(width 0)
					(fill yes)
				)
			)
		)
	)
	(footprint ""
		(layer "B.Cu")
		(at 241.6048 -57.995058 90)
		(property "Reference" "C500"
			(at 0 0 90)
			(layer "B.SilkS")
			(hide yes)
			(effects
				(font
					(size 1.27 1.27)
				)
				(justify mirror)
			)
		)
		(property "Value" "SCD1U16V1KX-1-GP"
			(at 2.8321 -1.7399 90)
			(unlocked yes)
			(layer "B.Fab")
			(hide yes)
			(effects
				(font
					(size 1.016 1.016)
					(thickness 0.1524)
				)
				(justify mirror)
			)
		)
		(property "Device Type" "C0201H13"
			(at 2.8321 -3.2639 90)
			(unlocked yes)
			(layer "B.Fab")
			(hide yes)
			(effects
				(font
					(size 1.016 1.016)
					(thickness 0.1524)
				)
				(justify mirror)
			)
		)
		(duplicate_pad_numbers_are_jumpers no)
		(fp_rect
			(start 0.2794 0.6477)
			(end -0.2794 -0.6477)
			(stroke
				(width 0)
				(type default)
			)
			(fill no)
			(layer "B.CrtYd")
		)
		(fp_rect
			(start 0.2794 0.6477)
			(end -0.2794 -0.6477)
			(stroke
				(width 0)
				(type default)
			)
			(fill no)
			(layer "B.Fab")
		)
		(pad "1" smd custom
			(at 0 -0.2794 270)
			(size 0.0762 0.0762)
			(layers "B.Cu" "B.Mask" "B.Paste")
			(net "DUT_AVD_TX")
			(options
				(clearance outline)
				(anchor circle)
			)
			(primitives
				(gr_poly
					(pts
						(arc
							(start 0.1524 0.127)
							(mid 0.137521 0.162921)
							(end 0.1016 0.1778)
						)
						(arc
							(start -0.1016 0.1778)
							(mid -0.137521 0.162921)
							(end -0.1524 0.127)
						)
						(arc
							(start -0.1524 -0.127)
							(mid -0.137521 -0.162921)
							(end -0.1016 -0.1778)
						)
						(arc
							(start 0.1016 -0.1778)
							(mid 0.137521 -0.162921)
							(end 0.1524 -0.127)
						)
					)
					(width 0)
					(fill yes)
				)
			)
		)
		(pad "2" smd custom
			(at 0 0.2794 270)
			(size 0.0762 0.0762)
			(layers "B.Cu" "B.Mask" "B.Paste")
			(net "GND")
			(options
				(clearance outline)
				(anchor circle)
			)
			(primitives
				(gr_poly
					(pts
						(arc
							(start 0.1524 0.127)
							(mid 0.137521 0.162921)
							(end 0.1016 0.1778)
						)
						(arc
							(start -0.1016 0.1778)
							(mid -0.137521 0.162921)
							(end -0.1524 0.127)
						)
						(arc
							(start -0.1524 -0.127)
							(mid -0.137521 -0.162921)
							(end -0.1016 -0.1778)
						)
						(arc
							(start 0.1016 -0.1778)
							(mid 0.137521 -0.162921)
							(end 0.1524 -0.127)
						)
					)
					(width 0)
					(fill yes)
				)
			)
		)
	)
	(footprint ""
		(layer "B.Cu")
		(at 137.332212 -199.753474)
		(property "Reference" "R3221"
			(at 0 0 0)
			(layer "B.SilkS")
			(hide yes)
			(effects
				(font
					(size 1.27 1.27)
				)
				(justify mirror)
			)
		)
		(property "Value" "0R2J-2-GP"
			(at -0.064008 -3.993896 0)
			(unlocked yes)
			(layer "B.Fab")
			(hide yes)
			(effects
				(font
					(size 1.016 1.016)
					(thickness 0.1524)
				)
				(justify mirror)
			)
		)
		(property "Device Type" "R402H16"
			(at -0.064008 -5.517896 0)
			(unlocked yes)
			(layer "B.Fab")
			(hide yes)
			(effects
				(font
					(size 1.016 1.016)
					(thickness 0.1524)
				)
				(justify mirror)
			)
		)
		(duplicate_pad_numbers_are_jumpers no)
		(fp_line
			(start -0.508 -0.9398)
			(end 0.508 -0.9398)
			(stroke
				(width 0.1524)
				(type default)
			)
			(layer "B.SilkS")
		)
		(fp_line
			(start 0.508 -0.9398)
			(end 0.508 0.9398)
			(stroke
				(width 0.1524)
				(type default)
			)
			(layer "B.SilkS")
		)
		(fp_rect
			(start 0.508 0.9398)
			(end -0.508 -0.9398)
			(stroke
				(width 0)
				(type default)
			)
			(fill no)
			(layer "B.CrtYd")
		)
		(fp_rect
			(start 0.508 0.9398)
			(end -0.508 -0.9398)
			(stroke
				(width 0)
				(type default)
			)
			(fill no)
			(layer "B.Fab")
		)
		(pad "1" smd custom
			(at 0 -0.4445 180)
			(size 0.1397 0.1397)
			(layers "B.Cu" "B.Mask" "B.Paste")
			(net "SSD_PERST_Y6")
			(options
				(clearance outline)
				(anchor circle)
			)
			(primitives
				(gr_poly
					(pts
						(arc
							(start -0.1778 0.2794)
							(mid -0.249642 0.249642)
							(end -0.2794 0.1778)
						)
						(arc
							(start -0.2794 -0.1778)
							(mid -0.249642 -0.249642)
							(end -0.1778 -0.2794)
						)
						(arc
							(start 0.1778 -0.2794)
							(mid 0.249642 -0.249642)
							(end 0.2794 -0.1778)
						)
						(arc
							(start 0.2794 0.1778)
							(mid 0.249642 0.249642)
							(end 0.1778 0.2794)
						)
					)
					(width 0)
					(fill yes)
				)
			)
		)
		(pad "2" smd custom
			(at 0 0.4445 180)
			(size 0.1397 0.1397)
			(layers "B.Cu" "B.Mask" "B.Paste")
			(net "SSD_PERST#6_R")
			(options
				(clearance outline)
				(anchor circle)
			)
			(primitives
				(gr_poly
					(pts
						(arc
							(start -0.1778 0.2794)
							(mid -0.249642 0.249642)
							(end -0.2794 0.1778)
						)
						(arc
							(start -0.2794 -0.1778)
							(mid -0.249642 -0.249642)
							(end -0.1778 -0.2794)
						)
						(arc
							(start 0.1778 -0.2794)
							(mid 0.249642 -0.249642)
							(end 0.2794 -0.1778)
						)
						(arc
							(start 0.2794 0.1778)
							(mid 0.249642 0.249642)
							(end 0.1778 0.2794)
						)
					)
					(width 0)
					(fill yes)
				)
			)
		)
	)
	(footprint ""
		(layer "B.Cu")
		(at 75.184 -149.479 -90)
		(property "Reference" "R194"
			(at 0 0 90)
			(layer "B.SilkS")
			(hide yes)
			(effects
				(font
					(size 1.27 1.27)
				)
				(justify mirror)
			)
		)
		(property "Value" "8K2R2J-3-GP"
			(at -0.064008 -3.993896 270)
			(unlocked yes)
			(layer "B.Fab")
			(hide yes)
			(effects
				(font
					(size 1.016 1.016)
					(thickness 0.1524)
				)
				(justify mirror)
			)
		)
		(property "Device Type" "R402H16"
			(at -0.064008 -5.517896 270)
			(unlocked yes)
			(layer "B.Fab")
			(hide yes)
			(effects
				(font
					(size 1.016 1.016)
					(thickness 0.1524)
				)
				(justify mirror)
			)
		)
		(duplicate_pad_numbers_are_jumpers no)
		(fp_line
			(start -0.508 -0.9398)
			(end 0.508 -0.9398)
			(stroke
				(width 0.1524)
				(type default)
			)
			(layer "B.SilkS")
		)
		(fp_line
			(start 0.508 -0.9398)
			(end 0.508 0.9398)
			(stroke
				(width 0.1524)
				(type default)
			)
			(layer "B.SilkS")
		)
		(fp_rect
			(start 0.508 0.9398)
			(end -0.508 -0.9398)
			(stroke
				(width 0)
				(type default)
			)
			(fill no)
			(layer "B.CrtYd")
		)
		(fp_rect
			(start 0.508 0.9398)
			(end -0.508 -0.9398)
			(stroke
				(width 0)
				(type default)
			)
			(fill no)
			(layer "B.Fab")
		)
		(pad "1" smd custom
			(at 0 -0.4445 90)
			(size 0.1397 0.1397)
			(layers "B.Cu" "B.Mask" "B.Paste")
			(net "P3V3_STBY")
			(options
				(clearance outline)
				(anchor circle)
			)
			(primitives
				(gr_poly
					(pts
						(arc
							(start -0.1778 0.2794)
							(mid -0.249642 0.249642)
							(end -0.2794 0.1778)
						)
						(arc
							(start -0.2794 -0.1778)
							(mid -0.249642 -0.249642)
							(end -0.1778 -0.2794)
						)
						(arc
							(start 0.1778 -0.2794)
							(mid 0.249642 -0.249642)
							(end 0.2794 -0.1778)
						)
						(arc
							(start 0.2794 0.1778)
							(mid 0.249642 0.249642)
							(end 0.1778 0.2794)
						)
					)
					(width 0)
					(fill yes)
				)
			)
		)
		(pad "2" smd custom
			(at 0 0.4445 90)
			(size 0.1397 0.1397)
			(layers "B.Cu" "B.Mask" "B.Paste")
			(net "EEPROM_A2_R")
			(options
				(clearance outline)
				(anchor circle)
			)
			(primitives
				(gr_poly
					(pts
						(arc
							(start -0.1778 0.2794)
							(mid -0.249642 0.249642)
							(end -0.2794 0.1778)
						)
						(arc
							(start -0.2794 -0.1778)
							(mid -0.249642 -0.249642)
							(end -0.1778 -0.2794)
						)
						(arc
							(start 0.1778 -0.2794)
							(mid 0.249642 -0.249642)
							(end 0.2794 -0.1778)
						)
						(arc
							(start 0.2794 0.1778)
							(mid 0.249642 0.249642)
							(end 0.1778 0.2794)
						)
					)
					(width 0)
					(fill yes)
				)
			)
		)
	)
)
